(kicad_pcb
	(version 20260206)
	(generator "pcbnew")
	(generator_version "10.0")
	(general
		(thickness 1.6)
		(legacy_teardrops no)
	)
	(paper "A4")
	(title_block
		(title "Bryce Canyon_IOM_IOC_16318-2_OCP.brd")
		(comment 1 "Bryce Canyon / footprints 1585-1592 of 1605")
	)
	(layers
		(0 "F.Cu" signal "TOP")
		(4 "In1.Cu" signal "L2GND")
		(6 "In2.Cu" signal "L3")
		(8 "In3.Cu" signal "L4VCC")
		(10 "In4.Cu" signal "L5VCC")
		(12 "In5.Cu" signal "L6")
		(14 "In6.Cu" signal "L7GND")
		(2 "B.Cu" signal "BOTTOM")
		(9 "F.Adhes" user "F.Adhesive")
		(11 "B.Adhes" user "B.Adhesive")
		(13 "F.Paste" user "Package Geometry/Pastemask Top")
		(15 "B.Paste" user "Package Geometry/Pastemask Bottom")
		(5 "F.SilkS" user "Ref Des/Silkscreen Top")
		(7 "B.SilkS" user "Ref Des/Silkscreen Bottom")
		(1 "F.Mask" user "Board Geometry/Soldermask Top")
		(3 "B.Mask" user "Board Geometry/Soldermask Bottom")
		(17 "Dwgs.User" user "User.Drawings")
		(19 "Cmts.User" user "User.Comments")
		(21 "Eco1.User" user "User.Eco1")
		(23 "Eco2.User" user "User.Eco2")
		(25 "Edge.Cuts" user "Board Geometry/Outline")
		(27 "Margin" user)
		(31 "F.CrtYd" user "Package Geometry/Place Bound Top")
		(29 "B.CrtYd" user "Package Geometry/Place Bound Bottom")
		(35 "F.Fab" user "Ref Des/Assembly Top")
		(33 "B.Fab" user "Ref Des/Assembly Bottom")
	)
	(footprint ""
		(layer "B.Cu")
		(at 180.594 -59.1312)
		(property "Reference" "TP164"
			(at 0 0 0)
			(layer "B.SilkS")
			(hide yes)
			(effects
				(font
					(size 1.27 1.27)
				)
				(justify mirror)
			)
		)
		(property "Value" "TPAD28-2-GP"
			(at 0.0127 -1.6637 0)
			(unlocked yes)
			(layer "B.Fab")
			(hide yes)
			(effects
				(font
					(size 1.016 1.016)
					(thickness 0.1524)
				)
				(justify mirror)
			)
		)
		(property "Device Type" "TPAD28"
			(at 0.0127 -3.1877 0)
			(unlocked yes)
			(layer "B.Fab")
			(hide yes)
			(effects
				(font
					(size 1.016 1.016)
					(thickness 0.1524)
				)
				(justify mirror)
			)
		)
		(duplicate_pad_numbers_are_jumpers no)
		(fp_poly
			(pts
				(arc
					(start 0.3556 0)
					(mid -0.3556 0)
					(end 0.3556 0)
				)
			)
			(stroke
				(width 0)
				(type default)
			)
			(fill no)
			(layer "B.CrtYd")
		)
		(fp_poly
			(pts
				(arc
					(start 0.6096 0)
					(mid -0.6096 0)
					(end 0.6096 0)
				)
			)
			(stroke
				(width 0)
				(type default)
			)
			(fill no)
			(layer "B.Fab")
		)
		(pad "1" smd circle
			(at 0 0 180)
			(size 0.7112 0.7112)
			(layers "B.Cu" "B.Mask" "B.Paste")
			(net "XM_ADDR_25")
		)
	)
	(footprint ""
		(layer "B.Cu")
		(at 41.9862 -134.0358 90)
		(property "Reference" "R373"
			(at 0 0 90)
			(layer "B.SilkS")
			(hide yes)
			(effects
				(font
					(size 1.27 1.27)
				)
				(justify mirror)
			)
		)
		(property "Value" "4K7R2F-GP"
			(at -0.064008 -3.993896 90)
			(unlocked yes)
			(layer "B.Fab")
			(hide yes)
			(effects
				(font
					(size 1.016 1.016)
					(thickness 0.1524)
				)
				(justify mirror)
			)
		)
		(property "Device Type" "R402H16"
			(at -0.064008 -5.517896 90)
			(unlocked yes)
			(layer "B.Fab")
			(hide yes)
			(effects
				(font
					(size 1.016 1.016)
					(thickness 0.1524)
				)
				(justify mirror)
			)
		)
		(duplicate_pad_numbers_are_jumpers no)
		(fp_line
			(start 0.508 -0.9398)
			(end 0.508 0.9398)
			(stroke
				(width 0.1524)
				(type default)
			)
			(layer "B.SilkS")
		)
		(fp_line
			(start -0.508 -0.9398)
			(end 0.508 -0.9398)
			(stroke
				(width 0.1524)
				(type default)
			)
			(layer "B.SilkS")
		)
		(fp_rect
			(start 0.508 0.9398)
			(end -0.508 -0.9398)
			(stroke
				(width 0)
				(type default)
			)
			(fill no)
			(layer "B.CrtYd")
		)
		(fp_rect
			(start 0.508 0.9398)
			(end -0.508 -0.9398)
			(stroke
				(width 0)
				(type default)
			)
			(fill no)
			(layer "B.Fab")
		)
		(pad "1" smd custom
			(at 0 -0.4445 270)
			(size 0.1397 0.1397)
			(layers "B.Cu" "B.Mask" "B.Paste")
			(net "P3V3_STBY")
			(options
				(clearance outline)
				(anchor circle)
			)
			(primitives
				(gr_poly
					(pts
						(arc
							(start -0.1778 0.2794)
							(mid -0.249642 0.249642)
							(end -0.2794 0.1778)
						)
						(arc
							(start -0.2794 -0.1778)
							(mid -0.249642 -0.249642)
							(end -0.1778 -0.2794)
						)
						(arc
							(start 0.1778 -0.2794)
							(mid 0.249642 -0.249642)
							(end 0.2794 -0.1778)
						)
						(arc
							(start 0.2794 0.1778)
							(mid 0.249642 0.249642)
							(end 0.1778 0.2794)
						)
					)
					(width 0)
					(fill yes)
				)
			)
		)
		(pad "2" smd custom
			(at 0 0.4445 270)
			(size 0.1397 0.1397)
			(layers "B.Cu" "B.Mask" "B.Paste")
			(net "BMC_GPIOS5")
			(options
				(clearance outline)
				(anchor circle)
			)
			(primitives
				(gr_poly
					(pts
						(arc
							(start -0.1778 0.2794)
							(mid -0.249642 0.249642)
							(end -0.2794 0.1778)
						)
						(arc
							(start -0.2794 -0.1778)
							(mid -0.249642 -0.249642)
							(end -0.1778 -0.2794)
						)
						(arc
							(start 0.1778 -0.2794)
							(mid 0.249642 -0.249642)
							(end 0.2794 -0.1778)
						)
						(arc
							(start 0.2794 0.1778)
							(mid 0.249642 0.249642)
							(end 0.1778 0.2794)
						)
					)
					(width 0)
					(fill yes)
				)
			)
		)
	)
	(footprint ""
		(layer "B.Cu")
		(at 50.103786 -146.684238 -90)
		(property "Reference" "C98"
			(at 0 0 90)
			(layer "B.SilkS")
			(hide yes)
			(effects
				(font
					(size 1.27 1.27)
				)
				(justify mirror)
			)
		)
		(property "Value" "SC1U16V3KX-5GP"
			(at 0 -2.8194 270)
			(unlocked yes)
			(layer "B.Fab")
			(hide yes)
			(effects
				(font
					(size 1.016 1.016)
					(thickness 0.1524)
				)
				(justify mirror)
			)
		)
		(property "Device Type" "C603H36"
			(at 0 -4.3434 270)
			(unlocked yes)
			(layer "B.Fab")
			(hide yes)
			(effects
				(font
					(size 1.016 1.016)
					(thickness 0.1524)
				)
				(justify mirror)
			)
		)
		(duplicate_pad_numbers_are_jumpers no)
		(fp_line
			(start -0.508 0)
			(end 0.508 0)
			(stroke
				(width 0.2032)
				(type default)
			)
			(layer "B.SilkS")
		)
		(fp_rect
			(start 0.5842 1.3335)
			(end -0.5842 -1.3335)
			(stroke
				(width 0)
				(type default)
			)
			(fill no)
			(layer "B.CrtYd")
		)
		(fp_rect
			(start 0.5842 1.3335)
			(end -0.5842 -1.3335)
			(stroke
				(width 0)
				(type default)
			)
			(fill no)
			(layer "B.Fab")
		)
		(pad "1" smd custom
			(at 0 -0.762 90)
			(size 0.2159 0.2159)
			(layers "B.Cu" "B.Mask" "B.Paste")
			(net "P3V3_STBY")
			(options
				(clearance outline)
				(anchor circle)
			)
			(primitives
				(gr_poly
					(pts
						(arc
							(start -0.3302 0.4318)
							(mid -0.402042 0.402042)
							(end -0.4318 0.3302)
						)
						(arc
							(start -0.4318 -0.3302)
							(mid -0.402042 -0.402042)
							(end -0.3302 -0.4318)
						)
						(arc
							(start 0.3302 -0.4318)
							(mid 0.402042 -0.402042)
							(end 0.4318 -0.3302)
						)
						(arc
							(start 0.4318 0.3302)
							(mid 0.402042 0.402042)
							(end 0.3302 0.4318)
						)
					)
					(width 0)
					(fill yes)
				)
			)
		)
		(pad "2" smd custom
			(at 0 0.762 90)
			(size 0.2159 0.2159)
			(layers "B.Cu" "B.Mask" "B.Paste")
			(net "GND")
			(options
				(clearance outline)
				(anchor circle)
			)
			(primitives
				(gr_poly
					(pts
						(arc
							(start -0.3302 0.4318)
							(mid -0.402042 0.402042)
							(end -0.4318 0.3302)
						)
						(arc
							(start -0.4318 -0.3302)
							(mid -0.402042 -0.402042)
							(end -0.3302 -0.4318)
						)
						(arc
							(start 0.3302 -0.4318)
							(mid 0.402042 -0.402042)
							(end 0.4318 -0.3302)
						)
						(arc
							(start 0.4318 0.3302)
							(mid 0.402042 0.402042)
							(end 0.3302 0.4318)
						)
					)
					(width 0)
					(fill yes)
				)
			)
		)
	)
	(footprint ""
		(layer "B.Cu")
		(at 163.83 -140.8938 180)
		(property "Reference" "C212"
			(at 0 0 0)
			(layer "B.SilkS")
			(hide yes)
			(effects
				(font
					(size 1.27 1.27)
				)
				(justify mirror)
			)
		)
		(property "Value" "SC1KP50V2KX-1GP"
			(at -1.1811 -2.7051 180)
			(unlocked yes)
			(layer "B.Fab")
			(hide yes)
			(effects
				(font
					(size 1.016 1.016)
					(thickness 0.1524)
				)
				(justify mirror)
			)
		)
		(property "Device Type" "C402H22"
			(at -1.1811 -4.2291 180)
			(unlocked yes)
			(layer "B.Fab")
			(hide yes)
			(effects
				(font
					(size 1.016 1.016)
					(thickness 0.1524)
				)
				(justify mirror)
			)
		)
		(duplicate_pad_numbers_are_jumpers no)
		(fp_rect
			(start 0.4318 0.9525)
			(end -0.4318 -0.9525)
			(stroke
				(width 0)
				(type default)
			)
			(fill no)
			(layer "B.CrtYd")
		)
		(fp_rect
			(start 0.4318 0.9525)
			(end -0.4318 -0.9525)
			(stroke
				(width 0)
				(type default)
			)
			(fill no)
			(layer "B.Fab")
		)
		(pad "1" smd custom
			(at 0 -0.4445)
			(size 0.1524 0.1524)
			(layers "B.Cu" "B.Mask" "B.Paste")
			(net "P1V8_STBY_VFB_R")
			(options
				(clearance outline)
				(anchor circle)
			)
			(primitives
				(gr_poly
					(pts
						(arc
							(start 0.3048 0.2032)
							(mid 0.275042 0.275042)
							(end 0.2032 0.3048)
						)
						(arc
							(start -0.2032 0.3048)
							(mid -0.275042 0.275042)
							(end -0.3048 0.2032)
						)
						(arc
							(start -0.3048 -0.2032)
							(mid -0.275042 -0.275042)
							(end -0.2032 -0.3048)
						)
						(arc
							(start 0.2032 -0.3048)
							(mid 0.275042 -0.275042)
							(end 0.3048 -0.2032)
						)
					)
					(width 0)
					(fill yes)
				)
			)
		)
		(pad "2" smd custom
			(at 0 0.4445)
			(size 0.1524 0.1524)
			(layers "B.Cu" "B.Mask" "B.Paste")
			(net "P1V8_STBY_VFB")
			(options
				(clearance outline)
				(anchor circle)
			)
			(primitives
				(gr_poly
					(pts
						(arc
							(start 0.3048 0.2032)
							(mid 0.275042 0.275042)
							(end 0.2032 0.3048)
						)
						(arc
							(start -0.2032 0.3048)
							(mid -0.275042 0.275042)
							(end -0.3048 0.2032)
						)
						(arc
							(start -0.3048 -0.2032)
							(mid -0.275042 -0.275042)
							(end -0.2032 -0.3048)
						)
						(arc
							(start 0.2032 -0.3048)
							(mid 0.275042 -0.275042)
							(end 0.3048 -0.2032)
						)
					)
					(width 0)
					(fill yes)
				)
			)
		)
	)
	(footprint ""
		(layer "B.Cu")
		(at 152.781 -92.3544 180)
		(property "Reference" "U41"
			(at 0 0 0)
			(layer "B.SilkS")
			(hide yes)
			(effects
				(font
					(size 1.27 1.27)
				)
				(justify mirror)
			)
		)
		(property "Value" "TPS3808G18DRVT-GP-U"
			(at 2.7813 -0.4572 180)
			(unlocked yes)
			(layer "B.Fab")
			(hide yes)
			(effects
				(font
					(size 1.016 1.016)
					(thickness 0.1524)
				)
				(justify mirror)
			)
		)
		(property "Device Type" "DFN6F2-G1711-UH32"
			(at 2.7813 -1.9812 180)
			(unlocked yes)
			(layer "B.Fab")
			(hide yes)
			(effects
				(font
					(size 1.016 1.016)
					(thickness 0.1524)
				)
				(justify mirror)
			)
		)
		(duplicate_pad_numbers_are_jumpers no)
		(fp_line
			(start 1.5113 1.7653)
			(end 0.7493 1.7653)
			(stroke
				(width 0.1524)
				(type default)
			)
			(layer "B.SilkS")
		)
		(fp_line
			(start 1.5113 1.0033)
			(end 1.5113 1.7653)
			(stroke
				(width 0.1524)
				(type default)
			)
			(layer "B.SilkS")
		)
		(fp_line
			(start 1.5113 -1.0033)
			(end 1.5113 -1.7653)
			(stroke
				(width 0.1524)
				(type default)
			)
			(layer "B.SilkS")
		)
		(fp_line
			(start 1.5113 -1.7653)
			(end 0.7493 -1.7653)
			(stroke
				(width 0.1524)
				(type default)
			)
			(layer "B.SilkS")
		)
		(fp_line
			(start 0 1.5113)
			(end 0 2.0193)
			(stroke
				(width 0.1524)
				(type default)
			)
			(layer "B.SilkS")
		)
		(fp_line
			(start -1.5113 1.7653)
			(end -0.7493 1.7653)
			(stroke
				(width 0.1524)
				(type default)
			)
			(layer "B.SilkS")
		)
		(fp_line
			(start -1.5113 1.0033)
			(end -1.5113 1.7653)
			(stroke
				(width 0.1524)
				(type default)
			)
			(layer "B.SilkS")
		)
		(fp_poly
			(pts
				(xy -0.7493 -1.7653) (xy -1.5113 -1.0033) (xy -1.5113 -1.7653)
			)
			(stroke
				(width 0)
				(type default)
			)
			(fill yes)
			(layer "B.SilkS")
		)
		(fp_rect
			(start 1.0033 1.0033)
			(end -1.0033 -1.0033)
			(stroke
				(width 0)
				(type default)
			)
			(fill no)
			(layer "B.CrtYd")
		)
		(fp_poly
			(pts
				(xy 1.5113 1.7653) (xy 1.5113 -1.7653) (xy -1.5113 -1.7653) (xy -1.5113 0.99822) (xy -1.0033 0.99822)
				(xy -1.0033 -1.0033) (xy 1.0033 -1.0033) (xy 1.0033 1.0033) (xy -1.5113 1.0033) (xy -1.5113 1.7653)
			)
			(stroke
				(width 0)
				(type default)
			)
			(fill no)
			(layer "B.CrtYd")
		)
		(fp_rect
			(start 1.5113 1.7653)
			(end -1.5113 -1.7653)
			(stroke
				(width 0)
				(type default)
			)
			(fill no)
			(layer "B.Fab")
		)
		(pad "1" smd rect
			(at -0.649986 -1.1303)
			(size 0.4064 0.508)
			(drill
				(offset 0 -0.127)
			)
			(layers "B.Cu" "B.Mask" "B.Paste")
			(net "P1V8_STBY")
		)
		(pad "2" smd rect
			(at 0 -1.1303)
			(size 0.4064 0.508)
			(drill
				(offset 0 -0.127)
			)
			(layers "B.Cu" "B.Mask" "B.Paste")
			(net "PWRGD_P0V975")
		)
		(pad "3" smd rect
			(at 0.649986 -1.1303)
			(size 0.4064 0.508)
			(drill
				(offset 0 -0.127)
			)
			(layers "B.Cu" "B.Mask" "B.Paste")
			(net "Net_189")
		)
		(pad "4" smd rect
			(at 0.649986 1.1303)
			(size 0.4064 0.508)
			(drill
				(offset 0 0.127)
			)
			(layers "B.Cu" "B.Mask" "B.Paste")
			(net "IOC_VREF_SET")
		)
		(pad "5" smd rect
			(at 0 1.1303)
			(size 0.4064 0.508)
			(drill
				(offset 0 0.127)
			)
			(layers "B.Cu" "B.Mask" "B.Paste")
			(net "GND")
		)
		(pad "6" smd rect
			(at -0.649986 1.1303)
			(size 0.4064 0.508)
			(drill
				(offset 0 0.127)
			)
			(layers "B.Cu" "B.Mask" "B.Paste")
			(net "IOC_RESET#")
		)
		(pad "7" smd rect
			(at 0 0)
			(size 1.7018 1.0922)
			(layers "B.Cu" "B.Mask" "B.Paste")
			(net "GND")
		)
	)
	(footprint ""
		(layer "B.Cu")
		(at 179.731416 -69.10578)
		(property "Reference" "TP128"
			(at 0 0 0)
			(layer "B.SilkS")
			(hide yes)
			(effects
				(font
					(size 1.27 1.27)
				)
				(justify mirror)
			)
		)
		(property "Value" "TPAD28-2-GP"
			(at 0.0127 -1.6637 0)
			(unlocked yes)
			(layer "B.Fab")
			(hide yes)
			(effects
				(font
					(size 1.016 1.016)
					(thickness 0.1524)
				)
				(justify mirror)
			)
		)
		(property "Device Type" "TPAD28"
			(at 0.0127 -3.1877 0)
			(unlocked yes)
			(layer "B.Fab")
			(hide yes)
			(effects
				(font
					(size 1.016 1.016)
					(thickness 0.1524)
				)
				(justify mirror)
			)
		)
		(duplicate_pad_numbers_are_jumpers no)
		(fp_poly
			(pts
				(arc
					(start 0.3556 0)
					(mid -0.3556 0)
					(end 0.3556 0)
				)
			)
			(stroke
				(width 0)
				(type default)
			)
			(fill no)
			(layer "B.CrtYd")
		)
		(fp_poly
			(pts
				(arc
					(start 0.6096 0)
					(mid -0.6096 0)
					(end 0.6096 0)
				)
			)
			(stroke
				(width 0)
				(type default)
			)
			(fill no)
			(layer "B.Fab")
		)
		(pad "1" smd circle
			(at 0 0 180)
			(size 0.7112 0.7112)
			(layers "B.Cu" "B.Mask" "B.Paste")
			(net "IOC_GPIO_35")
		)
	)
	(footprint ""
		(layer "B.Cu")
		(at 52.19446 -161.8615 -90)
		(property "Reference" "R411"
			(at 0 0 90)
			(layer "B.SilkS")
			(hide yes)
			(effects
				(font
					(size 1.27 1.27)
				)
				(justify mirror)
			)
		)
		(property "Value" "1KR2F-3-GP"
			(at -0.064008 -3.993896 270)
			(unlocked yes)
			(layer "B.Fab")
			(hide yes)
			(effects
				(font
					(size 1.016 1.016)
					(thickness 0.1524)
				)
				(justify mirror)
			)
		)
		(property "Device Type" "R402H16"
			(at -0.064008 -5.517896 270)
			(unlocked yes)
			(layer "B.Fab")
			(hide yes)
			(effects
				(font
					(size 1.016 1.016)
					(thickness 0.1524)
				)
				(justify mirror)
			)
		)
		(duplicate_pad_numbers_are_jumpers no)
		(fp_line
			(start -0.508 -0.9398)
			(end 0.508 -0.9398)
			(stroke
				(width 0.1524)
				(type default)
			)
			(layer "B.SilkS")
		)
		(fp_line
			(start 0.508 -0.9398)
			(end 0.508 0.9398)
			(stroke
				(width 0.1524)
				(type default)
			)
			(layer "B.SilkS")
		)
		(fp_rect
			(start 0.508 0.9398)
			(end -0.508 -0.9398)
			(stroke
				(width 0)
				(type default)
			)
			(fill no)
			(layer "B.CrtYd")
		)
		(fp_rect
			(start 0.508 0.9398)
			(end -0.508 -0.9398)
			(stroke
				(width 0)
				(type default)
			)
			(fill no)
			(layer "B.Fab")
		)
		(pad "1" smd custom
			(at 0 -0.4445 90)
			(size 0.1397 0.1397)
			(layers "B.Cu" "B.Mask" "B.Paste")
			(net "ADC_P1V5")
			(options
				(clearance outline)
				(anchor circle)
			)
			(primitives
				(gr_poly
					(pts
						(arc
							(start -0.1778 0.2794)
							(mid -0.249642 0.249642)
							(end -0.2794 0.1778)
						)
						(arc
							(start -0.2794 -0.1778)
							(mid -0.249642 -0.249642)
							(end -0.1778 -0.2794)
						)
						(arc
							(start 0.1778 -0.2794)
							(mid 0.249642 -0.249642)
							(end 0.2794 -0.1778)
						)
						(arc
							(start 0.2794 0.1778)
							(mid 0.249642 0.249642)
							(end 0.1778 0.2794)
						)
					)
					(width 0)
					(fill yes)
				)
			)
		)
		(pad "2" smd custom
			(at 0 0.4445 90)
			(size 0.1397 0.1397)
			(layers "B.Cu" "B.Mask" "B.Paste")
			(net "GND")
			(options
				(clearance outline)
				(anchor circle)
			)
			(primitives
				(gr_poly
					(pts
						(arc
							(start -0.1778 0.2794)
							(mid -0.249642 0.249642)
							(end -0.2794 0.1778)
						)
						(arc
							(start -0.2794 -0.1778)
							(mid -0.249642 -0.249642)
							(end -0.1778 -0.2794)
						)
						(arc
							(start 0.1778 -0.2794)
							(mid 0.249642 -0.249642)
							(end 0.2794 -0.1778)
						)
						(arc
							(start 0.2794 0.1778)
							(mid 0.249642 0.249642)
							(end 0.1778 0.2794)
						)
					)
					(width 0)
					(fill yes)
				)
			)
		)
	)
	(footprint ""
		(layer "B.Cu")
		(at 58.009536 -158.599886 180)
		(property "Reference" "C95"
			(at 0 0 0)
			(layer "B.SilkS")
			(hide yes)
			(effects
				(font
					(size 1.27 1.27)
				)
				(justify mirror)
			)
		)
		(property "Value" "SC1U16V3KX-5GP"
			(at 0 -2.8194 180)
			(unlocked yes)
			(layer "B.Fab")
			(hide yes)
			(effects
				(font
					(size 1.016 1.016)
					(thickness 0.1524)
				)
				(justify mirror)
			)
		)
		(property "Device Type" "C603H36"
			(at 0 -4.3434 180)
			(unlocked yes)
			(layer "B.Fab")
			(hide yes)
			(effects
				(font
					(size 1.016 1.016)
					(thickness 0.1524)
				)
				(justify mirror)
			)
		)
		(duplicate_pad_numbers_are_jumpers no)
		(fp_line
			(start -0.508 0)
			(end 0.508 0)
			(stroke
				(width 0.2032)
				(type default)
			)
			(layer "B.SilkS")
		)
		(fp_rect
			(start 0.5842 1.3335)
			(end -0.5842 -1.3335)
			(stroke
				(width 0)
				(type default)
			)
			(fill no)
			(layer "B.CrtYd")
		)
		(fp_rect
			(start 0.5842 1.3335)
			(end -0.5842 -1.3335)
			(stroke
				(width 0)
				(type default)
			)
			(fill no)
			(layer "B.Fab")
		)
		(pad "1" smd custom
			(at 0 -0.762)
			(size 0.2159 0.2159)
			(layers "B.Cu" "B.Mask" "B.Paste")
			(net "VPLLAV33")
			(options
				(clearance outline)
				(anchor circle)
			)
			(primitives
				(gr_poly
					(pts
						(arc
							(start -0.3302 0.4318)
							(mid -0.402042 0.402042)
							(end -0.4318 0.3302)
						)
						(arc
							(start -0.4318 -0.3302)
							(mid -0.402042 -0.402042)
							(end -0.3302 -0.4318)
						)
						(arc
							(start 0.3302 -0.4318)
							(mid 0.402042 -0.402042)
							(end 0.4318 -0.3302)
						)
						(arc
							(start 0.4318 0.3302)
							(mid 0.402042 0.402042)
							(end 0.3302 0.4318)
						)
					)
					(width 0)
					(fill yes)
				)
			)
		)
		(pad "2" smd custom
			(at 0 0.762)
			(size 0.2159 0.2159)
			(layers "B.Cu" "B.Mask" "B.Paste")
			(net "GND")
			(options
				(clearance outline)
				(anchor circle)
			)
			(primitives
				(gr_poly
					(pts
						(arc
							(start -0.3302 0.4318)
							(mid -0.402042 0.402042)
							(end -0.4318 0.3302)
						)
						(arc
							(start -0.4318 -0.3302)
							(mid -0.402042 -0.402042)
							(end -0.3302 -0.4318)
						)
						(arc
							(start 0.3302 -0.4318)
							(mid 0.402042 -0.402042)
							(end 0.4318 -0.3302)
						)
						(arc
							(start 0.4318 0.3302)
							(mid 0.402042 0.402042)
							(end 0.3302 0.4318)
						)
					)
					(width 0)
					(fill yes)
				)
			)
		)
	)
)
